(kicad_pcb
	(version 20260206)
	(generator "pcbnew")
	(generator_version "10.0")
	(general
		(thickness 1.6)
		(legacy_teardrops no)
	)
	(paper "A4")
	(title_block
		(title "01162023_DA0F0TEBIF0_F0T_Expander_BD_F_brd_V02_OCP.brd")
		(comment 1 "Grand Teton / footprints 938-945 of 9728")
	)
	(layers
		(0 "F.Cu" signal "TOP")
		(4 "In1.Cu" signal "GND")
		(6 "In2.Cu" signal "VCC")
		(8 "In3.Cu" signal "VCC1")
		(10 "In4.Cu" signal "GND1")
		(12 "In5.Cu" signal "IN1")
		(14 "In6.Cu" signal "GND2")
		(16 "In7.Cu" signal "IN2")
		(18 "In8.Cu" signal "GND3")
		(20 "In9.Cu" signal "IN3")
		(22 "In10.Cu" signal "GND4")
		(24 "In11.Cu" signal "IN4")
		(26 "In12.Cu" signal "GND5")
		(28 "In13.Cu" signal "IN5")
		(30 "In14.Cu" signal "GND6")
		(32 "In15.Cu" signal "IN6")
		(34 "In16.Cu" signal "GND7")
		(2 "B.Cu" signal "BOTTOM")
		(9 "F.Adhes" user "F.Adhesive")
		(11 "B.Adhes" user "B.Adhesive")
		(13 "F.Paste" user "Package Geometry/Pastemask Top")
		(15 "B.Paste" user "Package Geometry/Pastemask Bottom")
		(5 "F.SilkS" user "Ref Des/Silkscreen Top")
		(7 "B.SilkS" user "Ref Des/Silkscreen Bottom")
		(1 "F.Mask" user "Board Geometry/Soldermask Top")
		(3 "B.Mask" user "Board Geometry/Soldermask Bottom")
		(17 "Dwgs.User" user "User.Drawings")
		(19 "Cmts.User" user "User.Comments")
		(21 "Eco1.User" user "User.Eco1")
		(23 "Eco2.User" user "User.Eco2")
		(25 "Edge.Cuts" user "Board Geometry/Outline")
		(27 "Margin" user)
		(31 "F.CrtYd" user "Package Geometry/Place Bound Top")
		(29 "B.CrtYd" user "Package Geometry/Place Bound Bottom")
		(35 "F.Fab" user "Ref Des/Assembly Top")
		(33 "B.Fab" user "Ref Des/Assembly Bottom")
	)
	(footprint ""
		(layer "F.Cu")
		(at 374.543828 -47.92091)
		(property "Reference" "R636"
			(at 0 0 0)
			(layer "F.SilkS")
			(hide yes)
			(effects
				(font
					(size 1.27 1.27)
				)
			)
		)
		(property "Value" ""
			(at 0 0 0)
			(layer "F.Fab")
			(effects
				(font
					(size 1.27 1.27)
				)
			)
		)
		(duplicate_pad_numbers_are_jumpers no)
		(fp_line
			(start -0.7874 -0.4064)
			(end 0.7874 -0.4064)
			(stroke
				(width 0.1524)
				(type default)
			)
			(layer "F.SilkS")
		)
		(fp_line
			(start -0.7874 0.4064)
			(end -0.7874 -0.4064)
			(stroke
				(width 0.1524)
				(type default)
			)
			(layer "F.SilkS")
		)
		(fp_line
			(start 0.7874 -0.4064)
			(end 0.7874 0.4064)
			(stroke
				(width 0.1524)
				(type default)
			)
			(layer "F.SilkS")
		)
		(fp_line
			(start 0.7874 0.4064)
			(end -0.7874 0.4064)
			(stroke
				(width 0.1524)
				(type default)
			)
			(layer "F.SilkS")
		)
		(fp_line
			(start -0.67945 -0.305054)
			(end -0.12065 -0.305054)
			(stroke
				(width 0.1)
				(type default)
			)
			(layer "F.Fab")
		)
		(fp_line
			(start -0.67945 0.3048)
			(end -0.67945 -0.305054)
			(stroke
				(width 0.1)
				(type default)
			)
			(layer "F.Fab")
		)
		(fp_line
			(start -0.12065 -0.305054)
			(end -0.12065 -0.2794)
			(stroke
				(width 0.1)
				(type default)
			)
			(layer "F.Fab")
		)
		(fp_line
			(start -0.12065 -0.2794)
			(end 0.12065 -0.2794)
			(stroke
				(width 0.1)
				(type default)
			)
			(layer "F.Fab")
		)
		(fp_line
			(start -0.12065 0.2794)
			(end -0.12065 0.3048)
			(stroke
				(width 0.1)
				(type default)
			)
			(layer "F.Fab")
		)
		(fp_line
			(start -0.12065 0.3048)
			(end -0.67945 0.3048)
			(stroke
				(width 0.1)
				(type default)
			)
			(layer "F.Fab")
		)
		(fp_line
			(start 0.120396 0.2794)
			(end -0.12065 0.2794)
			(stroke
				(width 0.1)
				(type default)
			)
			(layer "F.Fab")
		)
		(fp_line
			(start 0.120396 0.3048)
			(end 0.120396 0.2794)
			(stroke
				(width 0.1)
				(type default)
			)
			(layer "F.Fab")
		)
		(fp_line
			(start 0.12065 -0.3048)
			(end 0.67945 -0.3048)
			(stroke
				(width 0.1)
				(type default)
			)
			(layer "F.Fab")
		)
		(fp_line
			(start 0.12065 -0.2794)
			(end 0.12065 -0.3048)
			(stroke
				(width 0.1)
				(type default)
			)
			(layer "F.Fab")
		)
		(fp_line
			(start 0.67945 -0.3048)
			(end 0.67945 0.3048)
			(stroke
				(width 0.1)
				(type default)
			)
			(layer "F.Fab")
		)
		(fp_line
			(start 0.67945 0.3048)
			(end 0.120396 0.3048)
			(stroke
				(width 0.1)
				(type default)
			)
			(layer "F.Fab")
		)
		(pad "1" smd circle
			(at -0.40005 0)
			(size 0 0)
			(layers "F.Cu" "F.Mask" "F.Paste")
			(net "P3V3_AUX")
		)
		(pad "2" smd circle
			(at 0.40005 0)
			(size 0 0)
			(layers "F.Cu" "F.Mask" "F.Paste")
			(net "SSD_8_15_ADC_ALERT_N")
		)
	)
	(footprint ""
		(layer "F.Cu")
		(at 332.045564 -350.098614 90)
		(property "Reference" "C532"
			(at 0 0 90)
			(layer "F.SilkS")
			(hide yes)
			(effects
				(font
					(size 1.27 1.27)
				)
			)
		)
		(property "Value" ""
			(at 0 0 90)
			(layer "F.Fab")
			(effects
				(font
					(size 1.27 1.27)
				)
			)
		)
		(duplicate_pad_numbers_are_jumpers no)
		(fp_line
			(start 0.299974 -0.150114)
			(end 0.299974 0.150114)
			(stroke
				(width 0.1)
				(type default)
			)
			(layer "F.Fab")
		)
		(fp_line
			(start -0.299974 -0.150114)
			(end 0.299974 -0.150114)
			(stroke
				(width 0.1)
				(type default)
			)
			(layer "F.Fab")
		)
		(fp_line
			(start 0.299974 0.150114)
			(end -0.299974 0.150114)
			(stroke
				(width 0.1)
				(type default)
			)
			(layer "F.Fab")
		)
		(fp_line
			(start -0.299974 0.150114)
			(end -0.299974 -0.150114)
			(stroke
				(width 0.1)
				(type default)
			)
			(layer "F.Fab")
		)
		(pad "1" smd rect
			(at -0.2667 0 90)
			(size 0.3048 0.381)
			(layers "F.Cu" "F.Mask" "F.Paste")
			(net "P5E_PEX2_STN5_TX_DN<89>")
		)
		(pad "2" smd rect
			(at 0.2667 0 90)
			(size 0.3048 0.381)
			(layers "F.Cu" "F.Mask" "F.Paste")
			(net "P5E_PEX2_STN5_TX_C_DN<89>")
		)
	)
	(footprint ""
		(layer "F.Cu")
		(at 456.399138 -385.543806)
		(property "Reference" "H43"
			(at -2.5146 -3.645154 0)
			(unlocked yes)
			(layer "F.SilkS")
			(effects
				(font
					(size 0.7874 0.5842)
					(thickness 0.1524)
				)
				(justify left)
			)
		)
		(property "Value" ""
			(at 0 0 0)
			(layer "F.Fab")
			(effects
				(font
					(size 1.27 1.27)
				)
			)
		)
		(duplicate_pad_numbers_are_jumpers no)
		(fp_circle
			(center 0 0)
			(end 2.4003 0)
			(stroke
				(width 0.1524)
				(type default)
			)
			(fill no)
			(layer "F.SilkS")
		)
		(fp_circle
			(center 0 0)
			(end 6.5913 0)
			(stroke
				(width 0.1524)
				(type default)
			)
			(fill no)
			(layer "B.SilkS")
		)
		(fp_circle
			(center 0 0)
			(end 6.5913 0)
			(stroke
				(width 0.1)
				(type default)
			)
			(fill no)
			(layer "B.Fab")
		)
		(fp_circle
			(center 0 0)
			(end 2.4003 0)
			(stroke
				(width 0.1)
				(type default)
			)
			(fill no)
			(layer "F.Fab")
		)
		(pad "" np_thru_hole circle
			(at 0 0)
			(size 3.175 3.175)
			(drill 3.175)
			(layers "*.Cu" "*.Mask")
			(clearance 0.381)
			(thermal_gap 0.381)
		)
		(zone
			(layers "F.Cu" "B.Cu" "In1.Cu" "In2.Cu" "In3.Cu" "In4.Cu" "In5.Cu" "In6.Cu"
				"In7.Cu" "In8.Cu" "In9.Cu" "In10.Cu" "In11.Cu" "In12.Cu" "In13.Cu" "In14.Cu"
				"In15.Cu" "In16.Cu"
			)
			(hatch none 0.5)
			(connect_pads
				(clearance 0)
			)
			(min_thickness 0.25)
			(keepout
				(tracks not_allowed)
				(vias allowed)
				(pads allowed)
				(copperpour not_allowed)
				(footprints allowed)
			)
			(placement
				(enabled no)
				(sheetname "")
			)
			(fill
				(thermal_gap 0.5)
				(thermal_bridge_width 0.5)
				(island_removal_mode 0)
			)
			(polygon
				(pts
					(arc
						(start 458.494638 -385.543806)
						(mid 454.303638 -385.543806)
						(end 458.494638 -385.543806)
					)
				)
			)
		)
	)
	(footprint ""
		(layer "F.Cu")
		(at 9.319768 -162.003994 90)
		(property "Reference" "PR6877"
			(at 0 0 90)
			(layer "F.SilkS")
			(hide yes)
			(effects
				(font
					(size 1.27 1.27)
				)
			)
		)
		(property "Value" ""
			(at 0 0 90)
			(layer "F.Fab")
			(effects
				(font
					(size 1.27 1.27)
				)
			)
		)
		(duplicate_pad_numbers_are_jumpers no)
		(fp_line
			(start 0.7874 -0.4064)
			(end 0.7874 0.4064)
			(stroke
				(width 0.1524)
				(type default)
			)
			(layer "F.SilkS")
		)
		(fp_line
			(start -0.7874 -0.4064)
			(end 0.7874 -0.4064)
			(stroke
				(width 0.1524)
				(type default)
			)
			(layer "F.SilkS")
		)
		(fp_line
			(start 0.7874 0.4064)
			(end -0.7874 0.4064)
			(stroke
				(width 0.1524)
				(type default)
			)
			(layer "F.SilkS")
		)
		(fp_line
			(start -0.7874 0.4064)
			(end -0.7874 -0.4064)
			(stroke
				(width 0.1524)
				(type default)
			)
			(layer "F.SilkS")
		)
		(fp_line
			(start -0.12065 -0.305054)
			(end -0.12065 -0.2794)
			(stroke
				(width 0.1)
				(type default)
			)
			(layer "F.Fab")
		)
		(fp_line
			(start -0.67945 -0.305054)
			(end -0.12065 -0.305054)
			(stroke
				(width 0.1)
				(type default)
			)
			(layer "F.Fab")
		)
		(fp_line
			(start 0.67945 -0.3048)
			(end 0.67945 0.3048)
			(stroke
				(width 0.1)
				(type default)
			)
			(layer "F.Fab")
		)
		(fp_line
			(start 0.12065 -0.3048)
			(end 0.67945 -0.3048)
			(stroke
				(width 0.1)
				(type default)
			)
			(layer "F.Fab")
		)
		(fp_line
			(start 0.12065 -0.2794)
			(end 0.12065 -0.3048)
			(stroke
				(width 0.1)
				(type default)
			)
			(layer "F.Fab")
		)
		(fp_line
			(start -0.12065 -0.2794)
			(end 0.12065 -0.2794)
			(stroke
				(width 0.1)
				(type default)
			)
			(layer "F.Fab")
		)
		(fp_line
			(start 0.120396 0.2794)
			(end -0.12065 0.2794)
			(stroke
				(width 0.1)
				(type default)
			)
			(layer "F.Fab")
		)
		(fp_line
			(start -0.12065 0.2794)
			(end -0.12065 0.3048)
			(stroke
				(width 0.1)
				(type default)
			)
			(layer "F.Fab")
		)
		(fp_line
			(start 0.67945 0.3048)
			(end 0.120396 0.3048)
			(stroke
				(width 0.1)
				(type default)
			)
			(layer "F.Fab")
		)
		(fp_line
			(start 0.120396 0.3048)
			(end 0.120396 0.2794)
			(stroke
				(width 0.1)
				(type default)
			)
			(layer "F.Fab")
		)
		(fp_line
			(start -0.12065 0.3048)
			(end -0.67945 0.3048)
			(stroke
				(width 0.1)
				(type default)
			)
			(layer "F.Fab")
		)
		(fp_line
			(start -0.67945 0.3048)
			(end -0.67945 -0.305054)
			(stroke
				(width 0.1)
				(type default)
			)
			(layer "F.Fab")
		)
		(pad "1" smd circle
			(at -0.40005 0 90)
			(size 0 0)
			(layers "F.Cu" "F.Mask" "F.Paste")
			(net "P12V_NIC0_CO_IMON_VR")
		)
		(pad "2" smd circle
			(at 0.40005 0 90)
			(size 0 0)
			(layers "F.Cu" "F.Mask" "F.Paste")
			(net "GND")
		)
	)
	(footprint ""
		(layer "F.Cu")
		(at 28.04922 -296.996612 -90)
		(property "Reference" "C3054"
			(at 0 0 270)
			(layer "F.SilkS")
			(hide yes)
			(effects
				(font
					(size 1.27 1.27)
				)
			)
		)
		(property "Value" ""
			(at 0 0 270)
			(layer "F.Fab")
			(effects
				(font
					(size 1.27 1.27)
				)
			)
		)
		(duplicate_pad_numbers_are_jumpers no)
		(fp_line
			(start -0.299974 0.150114)
			(end -0.299974 -0.150114)
			(stroke
				(width 0.1)
				(type default)
			)
			(layer "F.Fab")
		)
		(fp_line
			(start 0.299974 0.150114)
			(end -0.299974 0.150114)
			(stroke
				(width 0.1)
				(type default)
			)
			(layer "F.Fab")
		)
		(fp_line
			(start -0.299974 -0.150114)
			(end 0.299974 -0.150114)
			(stroke
				(width 0.1)
				(type default)
			)
			(layer "F.Fab")
		)
		(fp_line
			(start 0.299974 -0.150114)
			(end 0.299974 0.150114)
			(stroke
				(width 0.1)
				(type default)
			)
			(layer "F.Fab")
		)
		(pad "1" smd rect
			(at -0.2667 0 270)
			(size 0.3048 0.381)
			(layers "F.Cu" "F.Mask" "F.Paste")
			(net "P1V8_PLL0_PEX0")
		)
		(pad "2" smd rect
			(at 0.2667 0 270)
			(size 0.3048 0.381)
			(layers "F.Cu" "F.Mask" "F.Paste")
			(net "GND")
		)
	)
	(footprint ""
		(layer "F.Cu")
		(at 33.103312 -59.571636 90)
		(property "Reference" "PR261"
			(at 0 0 90)
			(layer "F.SilkS")
			(hide yes)
			(effects
				(font
					(size 1.27 1.27)
				)
			)
		)
		(property "Value" ""
			(at 0 0 90)
			(layer "F.Fab")
			(effects
				(font
					(size 1.27 1.27)
				)
			)
		)
		(duplicate_pad_numbers_are_jumpers no)
		(fp_line
			(start 0.7874 -0.4064)
			(end 0.7874 0.4064)
			(stroke
				(width 0.1524)
				(type default)
			)
			(layer "F.SilkS")
		)
		(fp_line
			(start -0.7874 -0.4064)
			(end 0.7874 -0.4064)
			(stroke
				(width 0.1524)
				(type default)
			)
			(layer "F.SilkS")
		)
		(fp_line
			(start 0.7874 0.4064)
			(end -0.7874 0.4064)
			(stroke
				(width 0.1524)
				(type default)
			)
			(layer "F.SilkS")
		)
		(fp_line
			(start -0.7874 0.4064)
			(end -0.7874 -0.4064)
			(stroke
				(width 0.1524)
				(type default)
			)
			(layer "F.SilkS")
		)
		(fp_line
			(start -0.12065 -0.305054)
			(end -0.12065 -0.2794)
			(stroke
				(width 0.1)
				(type default)
			)
			(layer "F.Fab")
		)
		(fp_line
			(start -0.67945 -0.305054)
			(end -0.12065 -0.305054)
			(stroke
				(width 0.1)
				(type default)
			)
			(layer "F.Fab")
		)
		(fp_line
			(start 0.67945 -0.3048)
			(end 0.67945 0.3048)
			(stroke
				(width 0.1)
				(type default)
			)
			(layer "F.Fab")
		)
		(fp_line
			(start 0.12065 -0.3048)
			(end 0.67945 -0.3048)
			(stroke
				(width 0.1)
				(type default)
			)
			(layer "F.Fab")
		)
		(fp_line
			(start 0.12065 -0.2794)
			(end 0.12065 -0.3048)
			(stroke
				(width 0.1)
				(type default)
			)
			(layer "F.Fab")
		)
		(fp_line
			(start -0.12065 -0.2794)
			(end 0.12065 -0.2794)
			(stroke
				(width 0.1)
				(type default)
			)
			(layer "F.Fab")
		)
		(fp_line
			(start 0.120396 0.2794)
			(end -0.12065 0.2794)
			(stroke
				(width 0.1)
				(type default)
			)
			(layer "F.Fab")
		)
		(fp_line
			(start -0.12065 0.2794)
			(end -0.12065 0.3048)
			(stroke
				(width 0.1)
				(type default)
			)
			(layer "F.Fab")
		)
		(fp_line
			(start 0.67945 0.3048)
			(end 0.120396 0.3048)
			(stroke
				(width 0.1)
				(type default)
			)
			(layer "F.Fab")
		)
		(fp_line
			(start 0.120396 0.3048)
			(end 0.120396 0.2794)
			(stroke
				(width 0.1)
				(type default)
			)
			(layer "F.Fab")
		)
		(fp_line
			(start -0.12065 0.3048)
			(end -0.67945 0.3048)
			(stroke
				(width 0.1)
				(type default)
			)
			(layer "F.Fab")
		)
		(fp_line
			(start -0.67945 0.3048)
			(end -0.67945 -0.305054)
			(stroke
				(width 0.1)
				(type default)
			)
			(layer "F.Fab")
		)
		(pad "1" smd circle
			(at -0.40005 0 90)
			(size 0 0)
			(layers "F.Cu" "F.Mask" "F.Paste")
			(net "P3V3_SSD1_OCP")
		)
		(pad "2" smd circle
			(at 0.40005 0 90)
			(size 0 0)
			(layers "F.Cu" "F.Mask" "F.Paste")
			(net "GND")
		)
	)
	(footprint ""
		(layer "F.Cu")
		(at 361.734862 -133.088126 180)
		(property "Reference" "PC305"
			(at 0 0 180)
			(layer "F.SilkS")
			(hide yes)
			(effects
				(font
					(size 1.27 1.27)
				)
			)
		)
		(property "Value" ""
			(at 0 0 180)
			(layer "F.Fab")
			(effects
				(font
					(size 1.27 1.27)
				)
			)
		)
		(duplicate_pad_numbers_are_jumpers no)
		(fp_line
			(start 1.524 0.762)
			(end -1.524 0.762)
			(stroke
				(width 0.1524)
				(type default)
			)
			(layer "F.SilkS")
		)
		(fp_line
			(start 1.524 -0.762)
			(end 1.524 0.762)
			(stroke
				(width 0.1524)
				(type default)
			)
			(layer "F.SilkS")
		)
		(fp_line
			(start -1.524 0.762)
			(end -1.524 -0.762)
			(stroke
				(width 0.1524)
				(type default)
			)
			(layer "F.SilkS")
		)
		(fp_line
			(start -1.524 -0.762)
			(end 1.524 -0.762)
			(stroke
				(width 0.1524)
				(type default)
			)
			(layer "F.SilkS")
		)
		(fp_line
			(start 1.1049 0.724916)
			(end 1.1049 -0.724916)
			(stroke
				(width 0.1)
				(type default)
			)
			(layer "F.Fab")
		)
		(fp_line
			(start 1.1049 -0.724916)
			(end -1.1049 -0.724916)
			(stroke
				(width 0.1)
				(type default)
			)
			(layer "F.Fab")
		)
		(fp_line
			(start -1.1049 0.724916)
			(end 1.1049 0.724916)
			(stroke
				(width 0.1)
				(type default)
			)
			(layer "F.Fab")
		)
		(fp_line
			(start -1.1049 -0.724916)
			(end -1.1049 0.724916)
			(stroke
				(width 0.1)
				(type default)
			)
			(layer "F.Fab")
		)
		(pad "1" smd rect
			(at -0.889 0)
			(size 1.016 1.27)
			(layers "F.Cu" "F.Mask" "F.Paste")
			(net "GND")
		)
		(pad "2" smd rect
			(at 0.889 0)
			(size 1.016 1.27)
			(layers "F.Cu" "F.Mask" "F.Paste")
			(net "P12V_AUX")
		)
	)
	(footprint ""
		(layer "F.Cu")
		(at 457.185014 -209.270092 90)
		(property "Reference" "J54"
			(at -4.139692 2.251456 90)
			(unlocked yes)
			(layer "F.SilkS")
			(effects
				(font
					(size 0.7874 0.5842)
					(thickness 0.1524)
				)
				(justify left)
			)
		)
		(property "Value" ""
			(at 0 0 90)
			(layer "F.Fab")
			(effects
				(font
					(size 1.27 1.27)
				)
			)
		)
		(duplicate_pad_numbers_are_jumpers no)
		(fp_line
			(start 3.999992 -1.500124)
			(end 3.999992 1.500124)
			(stroke
				(width 0.1524)
				(type default)
			)
			(layer "F.SilkS")
		)
		(fp_line
			(start 3.7338 -1.500124)
			(end 3.999992 -1.500124)
			(stroke
				(width 0.1524)
				(type default)
			)
			(layer "F.SilkS")
		)
		(fp_line
			(start 1.651 -1.500124)
			(end 1.8542 -1.500124)
			(stroke
				(width 0.1524)
				(type default)
			)
			(layer "F.SilkS")
		)
		(fp_line
			(start -1.8542 -1.500124)
			(end -1.651 -1.500124)
			(stroke
				(width 0.1524)
				(type default)
			)
			(layer "F.SilkS")
		)
		(fp_line
			(start -3.999992 -1.500124)
			(end -3.7338 -1.500124)
			(stroke
				(width 0.1524)
				(type default)
			)
			(layer "F.SilkS")
		)
		(fp_line
			(start 3.999992 1.500124)
			(end 1.0414 1.500124)
			(stroke
				(width 0.1524)
				(type default)
			)
			(layer "F.SilkS")
		)
		(fp_line
			(start -1.0414 1.500124)
			(end -3.999992 1.500124)
			(stroke
				(width 0.1524)
				(type default)
			)
			(layer "F.SilkS")
		)
		(fp_line
			(start -3.999992 1.500124)
			(end -3.999992 -1.500124)
			(stroke
				(width 0.1524)
				(type default)
			)
			(layer "F.SilkS")
		)
		(fp_poly
			(pts
				(xy -1.428242 -2.594102) (xy -1.943608 -3.624834) (xy -0.912876 -3.624834)
			)
			(stroke
				(width 0)
				(type default)
			)
			(fill yes)
			(layer "F.SilkS")
		)
		(fp_line
			(start 3.999992 -1.500124)
			(end 3.999992 1.500124)
			(stroke
				(width 0.1)
				(type default)
			)
			(layer "F.Fab")
		)
		(fp_line
			(start -3.999992 -1.500124)
			(end 3.999992 -1.500124)
			(stroke
				(width 0.1)
				(type default)
			)
			(layer "F.Fab")
		)
		(fp_line
			(start 3.999992 1.500124)
			(end -3.999992 1.500124)
			(stroke
				(width 0.1)
				(type default)
			)
			(layer "F.Fab")
		)
		(fp_line
			(start -3.999992 1.500124)
			(end -3.999992 -1.500124)
			(stroke
				(width 0.1)
				(type default)
			)
			(layer "F.Fab")
		)
		(fp_poly
			(pts
				(xy -1.299972 -1.78943) (xy -1.815338 -2.820162) (xy -0.784606 -2.820162)
			)
			(stroke
				(width 0)
				(type default)
			)
			(fill yes)
			(layer "F.Fab")
		)
		(pad "1" smd rect
			(at -1.299972 -0.890016 90)
			(size 0.4318 1.4986)
			(layers "F.Cu" "F.Mask" "F.Paste")
			(net "USB_VBUS_CONN")
		)
		(pad "2" smd rect
			(at -0.649986 -0.890016 90)
			(size 0.4318 1.4986)
			(layers "F.Cu" "F.Mask" "F.Paste")
			(net "USB2_FT4232_MUX_D_DN")
		)
		(pad "3" smd rect
			(at 0 -0.890016 90)
			(size 0.4318 1.4986)
			(layers "F.Cu" "F.Mask" "F.Paste")
			(net "USB2_FT4232_MUX_D_DP")
		)
		(pad "4" smd rect
			(at 0.649986 -0.890016 90)
			(size 0.4318 1.4986)
			(layers "F.Cu" "F.Mask" "F.Paste")
			(net "Net_2681")
		)
		(pad "5" smd rect
			(at 1.299972 -0.890016 90)
			(size 0.4318 1.4986)
			(layers "F.Cu" "F.Mask" "F.Paste")
			(net "GND")
		)
		(pad "G1" thru_hole oval
			(at -2.800096 -1.139952 180)
			(size 1.1176 1.8034)
			(drill oval 0.508 1.2192)
			(layers "*.Cu" "*.Mask")
			(remove_unused_layers no)
			(net "GND")
			(clearance 0.0762)
			(thermal_gap 0.0762)
		)
		(pad "G2" thru_hole oval
			(at 2.800096 -1.139952 180)
			(size 1.1176 1.8034)
			(drill oval 0.508 1.2192)
			(layers "*.Cu" "*.Mask")
			(remove_unused_layers no)
			(net "GND")
			(clearance 0.0762)
			(thermal_gap 0.0762)
		)
		(pad "G3" thru_hole oval
			(at 0 1.009904 180)
			(size 1.1176 2.2098)
			(drill oval 0.508 1.6002)
			(layers "*.Cu" "*.Mask")
			(remove_unused_layers no)
			(net "GND")
			(clearance 0.0762)
			(thermal_gap 0.0762)
		)
	)
)
